(kicad_pcb
	(version 20241229)
	(generator "pcbnew")
	(generator_version "9.0")
	(general
		(thickness 1.61)
		(legacy_teardrops no)
	)
	(paper "A3")
	(title_block
		(title "RDIMM DDR5 Tester")
		(date "2026-05-21")
		(rev "2.2.0")
		(company "Antmicro")
		(comment 9 "footprints 528-532 of 796")
	)
	(layers
		(0 "F.Cu" signal)
		(4 "In1.Cu" power)
		(6 "In2.Cu" mixed)
		(8 "In3.Cu" power)
		(10 "In4.Cu" mixed)
		(12 "In5.Cu" power)
		(14 "In6.Cu" mixed)
		(16 "In7.Cu" power)
		(18 "In8.Cu" power)
		(20 "In9.Cu" mixed)
		(22 "In10.Cu" power)
		(2 "B.Cu" signal)
		(9 "F.Adhes" user "F.Adhesive")
		(11 "B.Adhes" user "B.Adhesive")
		(13 "F.Paste" user)
		(15 "B.Paste" user)
		(5 "F.SilkS" user "F.Silkscreen")
		(7 "B.SilkS" user "B.Silkscreen")
		(1 "F.Mask" user)
		(3 "B.Mask" user)
		(17 "Dwgs.User" user "User.Drawings")
		(19 "Cmts.User" user "User.Comments")
		(21 "Eco1.User" user "User.Eco1")
		(23 "Eco2.User" user "User.Eco2")
		(25 "Edge.Cuts" user)
		(27 "Margin" user)
		(31 "F.CrtYd" user "F.Courtyard")
		(29 "B.CrtYd" user "B.Courtyard")
		(35 "F.Fab" user)
		(33 "B.Fab" user)
	)
	(footprint "antmicro-footprints:C_0402_1005Metric_EIA"
		(layer "B.Cu")
		(at 191 154.5 90)
		(descr "Capacitor SMD 0402 (1005 Metric), square (rectangular) end terminal, IPC_7351 nominal, (Body size source: IPC-SM-782 page 76, https://www.pcb-3d.com/wordpress/wp-content/uploads/ipc-sm-782a_amendment_1_and_2.pdf)")
		(tags "capacitor 0402")
		(property "Reference" "C246"
			(at 10.25 -30.625 90)
			(layer "B.SilkS")
			(effects
				(font
					(size 0.7 0.7)
					(thickness 0.15)
				)
				(justify right bottom mirror)
			)
		)
		(property "Value" "C_1u_25V_0402"
			(at 0 -1.169 90)
			(layer "B.Fab")
			(effects
				(font
					(size 0.7 0.7)
					(thickness 0.15)
				)
				(justify right bottom mirror)
			)
		)
		(property "Datasheet" "https://www.murata.com/products/productdetail?partno=GRM155R61E105KE11%23"
			(at 0 0 90)
			(layer "F.Fab")
			(hide yes)
			(effects
				(font
					(size 1.27 1.27)
					(thickness 0.15)
				)
			)
		)
		(property "MPN" "GRM155R61E105KE11J"
			(at 0 0 90)
			(unlocked yes)
			(layer "B.Fab")
			(hide yes)
			(effects
				(font
					(size 1 1)
					(thickness 0.15)
				)
				(justify mirror)
			)
		)
		(property "Manufacturer" "Murata"
			(at 0 0 90)
			(unlocked yes)
			(layer "B.Fab")
			(hide yes)
			(effects
				(font
					(size 1 1)
					(thickness 0.15)
				)
				(justify mirror)
			)
		)
		(property "License" "Apache-2.0"
			(at 0 0 90)
			(unlocked yes)
			(layer "B.Fab")
			(hide yes)
			(effects
				(font
					(size 1 1)
					(thickness 0.15)
				)
				(justify mirror)
			)
		)
		(property "Author" "Antmicro"
			(at 0 0 90)
			(unlocked yes)
			(layer "B.Fab")
			(hide yes)
			(effects
				(font
					(size 1 1)
					(thickness 0.15)
				)
				(justify mirror)
			)
		)
		(property "Val" "1u"
			(at 0 0 90)
			(unlocked yes)
			(layer "B.Fab")
			(hide yes)
			(effects
				(font
					(size 1 1)
					(thickness 0.15)
				)
				(justify mirror)
			)
		)
		(property "Voltage" "25V"
			(at 0 0 90)
			(unlocked yes)
			(layer "B.Fab")
			(hide yes)
			(effects
				(font
					(size 1 1)
					(thickness 0.15)
				)
				(justify mirror)
			)
		)
		(property "Dielectric" "X5R"
			(at 0 0 90)
			(unlocked yes)
			(layer "B.Fab")
			(hide yes)
			(effects
				(font
					(size 1 1)
					(thickness 0.15)
				)
				(justify mirror)
			)
		)
		(sheetname "/FPGA power/")
		(sheetfile "fpga-power.kicad_sch")
		(attr smd)
		(fp_rect
			(start -0.95 0.45)
			(end 0.95 -0.45)
			(stroke
				(width 0.05)
				(type default)
			)
			(fill no)
			(layer "B.CrtYd")
		)
		(fp_line
			(start 0.498 -0.248)
			(end -0.5 -0.248)
			(stroke
				(width 0.15)
				(type solid)
			)
			(layer "B.Fab")
		)
		(fp_line
			(start -0.5 -0.248)
			(end -0.5 0.25)
			(stroke
				(width 0.15)
				(type solid)
			)
			(layer "B.Fab")
		)
		(fp_line
			(start 0.498 0.25)
			(end 0.498 -0.248)
			(stroke
				(width 0.15)
				(type solid)
			)
			(layer "B.Fab")
		)
		(fp_line
			(start -0.5 0.25)
			(end 0.498 0.25)
			(stroke
				(width 0.15)
				(type solid)
			)
			(layer "B.Fab")
		)
		(fp_text user "Author: Antmicro"
			(at -0.9656 -5.569 270)
			(layer "B.Fab")
			(effects
				(font
					(size 0.7 0.7)
					(thickness 0.15)
				)
				(justify left bottom mirror)
			)
		)
		(fp_text user "${REFERENCE}"
			(at -0.9656 -3.169 270)
			(layer "B.Fab")
			(effects
				(font
					(size 0.7 0.7)
					(thickness 0.15)
				)
				(justify left bottom mirror)
			)
		)
		(fp_text user "License: Apache-2.0"
			(at -0.9656 -4.369 270)
			(layer "B.Fab")
			(effects
				(font
					(size 0.7 0.7)
					(thickness 0.15)
				)
				(justify left bottom mirror)
			)
		)
		(pad "1" smd roundrect
			(at -0.5 0)
			(size 0.6 0.6)
			(layers "B.Cu" "B.Mask" "B.Paste")
			(roundrect_rratio 0.25)
			(net 1 "GND")
			(pintype "passive")
		)
		(pad "2" smd roundrect
			(at 0.498 0 90)
			(size 0.6 0.6)
			(layers "B.Cu" "B.Mask" "B.Paste")
			(roundrect_rratio 0.25)
			(net 553 "+0V85")
			(pintype "passive")
		)
	)
	(footprint "antmicro-footprints:C_0402_1005Metric_EIA"
		(layer "B.Cu")
		(at 178 149.5 90)
		(descr "Capacitor SMD 0402 (1005 Metric), square (rectangular) end terminal, IPC_7351 nominal, (Body size source: IPC-SM-782 page 76, https://www.pcb-3d.com/wordpress/wp-content/uploads/ipc-sm-782a_amendment_1_and_2.pdf)")
		(tags "capacitor 0402")
		(property "Reference" "C91"
			(at -1.125 -0.5 90)
			(layer "B.SilkS")
			(effects
				(font
					(size 0.7 0.7)
					(thickness 0.15)
				)
				(justify right bottom mirror)
			)
		)
		(property "Value" "C_100n_0402"
			(at 0 -1.169 90)
			(layer "B.Fab")
			(effects
				(font
					(size 0.7 0.7)
					(thickness 0.15)
				)
				(justify right bottom mirror)
			)
		)
		(property "Datasheet" "https://www.murata.com/products/productdetail?partno=GRM155R61H104KE14%23"
			(at 0 0 90)
			(layer "F.Fab")
			(hide yes)
			(effects
				(font
					(size 1.27 1.27)
					(thickness 0.15)
				)
			)
		)
		(property "MPN" "GRM155R61H104KE14D"
			(at 0 0 90)
			(unlocked yes)
			(layer "B.Fab")
			(hide yes)
			(effects
				(font
					(size 1 1)
					(thickness 0.15)
				)
				(justify mirror)
			)
		)
		(property "Manufacturer" "Murata"
			(at 0 0 90)
			(unlocked yes)
			(layer "B.Fab")
			(hide yes)
			(effects
				(font
					(size 1 1)
					(thickness 0.15)
				)
				(justify mirror)
			)
		)
		(property "License" "Apache-2.0"
			(at 0 0 90)
			(unlocked yes)
			(layer "B.Fab")
			(hide yes)
			(effects
				(font
					(size 1 1)
					(thickness 0.15)
				)
				(justify mirror)
			)
		)
		(property "Author" "Antmicro"
			(at 0 0 90)
			(unlocked yes)
			(layer "B.Fab")
			(hide yes)
			(effects
				(font
					(size 1 1)
					(thickness 0.15)
				)
				(justify mirror)
			)
		)
		(property "Val" "100n"
			(at 0 0 90)
			(unlocked yes)
			(layer "B.Fab")
			(hide yes)
			(effects
				(font
					(size 1 1)
					(thickness 0.15)
				)
				(justify mirror)
			)
		)
		(property "Voltage" "50V"
			(at 0 0 90)
			(unlocked yes)
			(layer "B.Fab")
			(hide yes)
			(effects
				(font
					(size 1 1)
					(thickness 0.15)
				)
				(justify mirror)
			)
		)
		(property "Dielectric" "X5R"
			(at 0 0 90)
			(unlocked yes)
			(layer "B.Fab")
			(hide yes)
			(effects
				(font
					(size 1 1)
					(thickness 0.15)
				)
				(justify mirror)
			)
		)
		(sheetname "/FPGA power/")
		(sheetfile "fpga-power.kicad_sch")
		(attr smd)
		(fp_rect
			(start -0.95 0.45)
			(end 0.95 -0.45)
			(stroke
				(width 0.05)
				(type default)
			)
			(fill no)
			(layer "B.CrtYd")
		)
		(fp_line
			(start 0.498 -0.248)
			(end -0.5 -0.248)
			(stroke
				(width 0.15)
				(type solid)
			)
			(layer "B.Fab")
		)
		(fp_line
			(start -0.5 -0.248)
			(end -0.5 0.25)
			(stroke
				(width 0.15)
				(type solid)
			)
			(layer "B.Fab")
		)
		(fp_line
			(start 0.498 0.25)
			(end 0.498 -0.248)
			(stroke
				(width 0.15)
				(type solid)
			)
			(layer "B.Fab")
		)
		(fp_line
			(start -0.5 0.25)
			(end 0.498 0.25)
			(stroke
				(width 0.15)
				(type solid)
			)
			(layer "B.Fab")
		)
		(fp_text user "${REFERENCE}"
			(at -0.9656 -3.169 270)
			(layer "B.Fab")
			(effects
				(font
					(size 0.7 0.7)
					(thickness 0.15)
				)
				(justify left bottom mirror)
			)
		)
		(fp_text user "License: Apache-2.0"
			(at -0.9656 -4.369 270)
			(layer "B.Fab")
			(effects
				(font
					(size 0.7 0.7)
					(thickness 0.15)
				)
				(justify left bottom mirror)
			)
		)
		(fp_text user "Author: Antmicro"
			(at -0.9656 -5.569 270)
			(layer "B.Fab")
			(effects
				(font
					(size 0.7 0.7)
					(thickness 0.15)
				)
				(justify left bottom mirror)
			)
		)
		(pad "1" smd roundrect
			(at -0.5 0)
			(size 0.6 0.6)
			(layers "B.Cu" "B.Mask" "B.Paste")
			(roundrect_rratio 0.25)
			(net 1 "GND")
			(pintype "passive")
		)
		(pad "2" smd roundrect
			(at 0.498 0 90)
			(size 0.6 0.6)
			(layers "B.Cu" "B.Mask" "B.Paste")
			(roundrect_rratio 0.25)
			(net 797 "+1V8")
			(pintype "passive")
		)
	)
	(footprint "antmicro-footprints:R_0402_1005Metric"
		(layer "B.Cu")
		(at 183 136.8 90)
		(descr "Resistor SMD 0402")
		(tags "resistor SMD 0402")
		(property "Reference" "R260"
			(at 2.3 0 270)
			(layer "B.SilkS")
			(effects
				(font
					(size 0.7 0.7)
					(thickness 0.15)
				)
				(justify mirror)
			)
		)
		(property "Value" "R_0R_0402"
			(at -1.011843 -1.772047 270)
			(layer "B.Fab")
			(effects
				(font
					(size 0.7 0.7)
					(thickness 0.15)
				)
				(justify left bottom mirror)
			)
		)
		(property "Datasheet" "https://industrial.panasonic.com/cdbs/www-data/pdf/RDA0000/AOA0000C301.pdf"
			(at 0 0 270)
			(layer "B.Fab")
			(hide yes)
			(effects
				(font
					(size 1.27 1.27)
					(thickness 0.15)
				)
				(justify mirror)
			)
		)
		(property "MPN" "ERJ2GE0R00X"
			(at 0 0 90)
			(unlocked yes)
			(layer "B.Fab")
			(hide yes)
			(effects
				(font
					(size 1 1)
					(thickness 0.15)
				)
				(justify mirror)
			)
		)
		(property "Manufacturer" "Panasonic"
			(at 0 0 90)
			(unlocked yes)
			(layer "B.Fab")
			(hide yes)
			(effects
				(font
					(size 1 1)
					(thickness 0.15)
				)
				(justify mirror)
			)
		)
		(property "License" "Apache-2.0"
			(at 0 0 90)
			(unlocked yes)
			(layer "B.Fab")
			(hide yes)
			(effects
				(font
					(size 1 1)
					(thickness 0.15)
				)
				(justify mirror)
			)
		)
		(property "Author" "Antmicro"
			(at 0 0 90)
			(unlocked yes)
			(layer "B.Fab")
			(hide yes)
			(effects
				(font
					(size 1 1)
					(thickness 0.15)
				)
				(justify mirror)
			)
		)
		(property "Val" "0R"
			(at 0 0 90)
			(unlocked yes)
			(layer "B.Fab")
			(hide yes)
			(effects
				(font
					(size 1 1)
					(thickness 0.15)
				)
				(justify mirror)
			)
		)
		(property "Tolerance" "~"
			(at 0 0 90)
			(unlocked yes)
			(layer "B.Fab")
			(hide yes)
			(effects
				(font
					(size 1 1)
					(thickness 0.15)
				)
				(justify mirror)
			)
		)
		(property "Current" "1A"
			(at 0 0 90)
			(unlocked yes)
			(layer "B.Fab")
			(hide yes)
			(effects
				(font
					(size 1 1)
					(thickness 0.15)
				)
				(justify mirror)
			)
		)
		(sheetname "/FPGA banks HP/")
		(sheetfile "fpga-hp-banks.kicad_sch")
		(attr smd)
		(fp_rect
			(start -0.925 0.47)
			(end 0.925 -0.47)
			(stroke
				(width 0.05)
				(type default)
			)
			(fill no)
			(layer "B.CrtYd")
		)
		(fp_rect
			(start -0.5 0.25)
			(end 0.5 -0.25)
			(stroke
				(width 0.15)
				(type solid)
			)
			(fill no)
			(layer "B.Fab")
		)
		(fp_text user "License: Apache-2.0"
			(at -0.95 -5.169 270)
			(layer "B.Fab")
			(effects
				(font
					(size 0.7 0.7)
					(thickness 0.15)
				)
				(justify left bottom mirror)
			)
		)
		(fp_text user "Author: Antmicro"
			(at -0.95 -4.169 270)
			(layer "B.Fab")
			(effects
				(font
					(size 0.7 0.7)
					(thickness 0.15)
				)
				(justify left bottom mirror)
			)
		)
		(fp_text user "${REFERENCE}"
			(at -0.95 -3.168 270)
			(layer "B.Fab")
			(effects
				(font
					(size 0.7 0.7)
					(thickness 0.15)
				)
				(justify left bottom mirror)
			)
		)
		(pad "1" smd roundrect
			(at -0.48 0 90)
			(size 0.59 0.64)
			(layers "B.Cu" "B.Mask" "B.Paste")
			(roundrect_rratio 0.25)
			(net 546 "/FPGA banks HP/VREF_67")
			(pintype "passive")
		)
		(pad "2" smd roundrect
			(at 0.48 0 90)
			(size 0.59 0.64)
			(layers "B.Cu" "B.Mask" "B.Paste")
			(roundrect_rratio 0.25)
			(net 826 "/FPGA banks HP/VREF")
			(pintype "passive")
		)
	)
	(footprint "antmicro-footprints:R_0402_1005Metric"
		(layer "B.Cu")
		(at 234.05 132.81 -90)
		(descr "Resistor SMD 0402")
		(tags "resistor SMD 0402")
		(property "Reference" "R126"
			(at -4.06 -0.25 90)
			(layer "B.SilkS")
			(effects
				(font
					(size 0.7 0.7)
					(thickness 0.15)
				)
				(justify left bottom mirror)
			)
		)
		(property "Value" "R_0R_0402"
			(at -1.011843 -1.772047 90)
			(layer "B.Fab")
			(effects
				(font
					(size 0.7 0.7)
					(thickness 0.15)
				)
				(justify left bottom mirror)
			)
		)
		(property "Datasheet" "https://industrial.panasonic.com/cdbs/www-data/pdf/RDA0000/AOA0000C301.pdf"
			(at 0 0 270)
			(layer "F.Fab")
			(hide yes)
			(effects
				(font
					(size 1.27 1.27)
					(thickness 0.15)
				)
			)
		)
		(property "MPN" "ERJ2GE0R00X"
			(at 0 0 270)
			(unlocked yes)
			(layer "B.Fab")
			(hide yes)
			(effects
				(font
					(size 1 1)
					(thickness 0.15)
				)
				(justify mirror)
			)
		)
		(property "Manufacturer" "Panasonic"
			(at 0 0 270)
			(unlocked yes)
			(layer "B.Fab")
			(hide yes)
			(effects
				(font
					(size 1 1)
					(thickness 0.15)
				)
				(justify mirror)
			)
		)
		(property "License" "Apache-2.0"
			(at 0 0 270)
			(unlocked yes)
			(layer "B.Fab")
			(hide yes)
			(effects
				(font
					(size 1 1)
					(thickness 0.15)
				)
				(justify mirror)
			)
		)
		(property "Author" "Antmicro"
			(at 0 0 270)
			(unlocked yes)
			(layer "B.Fab")
			(hide yes)
			(effects
				(font
					(size 1 1)
					(thickness 0.15)
				)
				(justify mirror)
			)
		)
		(property "Val" "0R"
			(at 0 0 270)
			(unlocked yes)
			(layer "B.Fab")
			(hide yes)
			(effects
				(font
					(size 1 1)
					(thickness 0.15)
				)
				(justify mirror)
			)
		)
		(property "Tolerance" "~"
			(at 0 0 270)
			(unlocked yes)
			(layer "B.Fab")
			(hide yes)
			(effects
				(font
					(size 1 1)
					(thickness 0.15)
				)
				(justify mirror)
			)
		)
		(property "Current" "1A"
			(at 0 0 270)
			(unlocked yes)
			(layer "B.Fab")
			(hide yes)
			(effects
				(font
					(size 1 1)
					(thickness 0.15)
				)
				(justify mirror)
			)
		)
		(sheetname "/I^{2}C + I3C/")
		(sheetfile "i2c.kicad_sch")
		(attr smd exclude_from_bom dnp)
		(fp_rect
			(start -0.925 0.47)
			(end 0.925 -0.47)
			(stroke
				(width 0.05)
				(type default)
			)
			(fill no)
			(layer "B.CrtYd")
		)
		(fp_rect
			(start -0.5 0.25)
			(end 0.5 -0.25)
			(stroke
				(width 0.15)
				(type solid)
			)
			(fill no)
			(layer "B.Fab")
		)
		(fp_text user "${REFERENCE}"
			(at -0.95 -3.168 90)
			(layer "B.Fab")
			(effects
				(font
					(size 0.7 0.7)
					(thickness 0.15)
				)
				(justify left bottom mirror)
			)
		)
		(fp_text user "License: Apache-2.0"
			(at -0.95 -5.169 90)
			(layer "B.Fab")
			(effects
				(font
					(size 0.7 0.7)
					(thickness 0.15)
				)
				(justify left bottom mirror)
			)
		)
		(fp_text user "Author: Antmicro"
			(at -0.95 -4.169 90)
			(layer "B.Fab")
			(effects
				(font
					(size 0.7 0.7)
					(thickness 0.15)
				)
				(justify left bottom mirror)
			)
		)
		(pad "1" smd roundrect
			(at -0.48 0 270)
			(size 0.59 0.64)
			(layers "B.Cu" "B.Mask" "B.Paste")
			(roundrect_rratio 0.25)
			(net 473 "Net-(R126-Pad1)")
			(pintype "passive")
		)
		(pad "2" smd roundrect
			(at 0.48 0 270)
			(size 0.59 0.64)
			(layers "B.Cu" "B.Mask" "B.Paste")
			(roundrect_rratio 0.25)
			(net 201 "VDDSPD")
			(pintype "passive")
		)
	)
	(footprint "antmicro-footprints:R_0402_1005Metric"
		(layer "B.Cu")
		(at 184 136.8 90)
		(descr "Resistor SMD 0402")
		(tags "resistor SMD 0402")
		(property "Reference" "R259"
			(at 2.3 0 270)
			(layer "B.SilkS")
			(effects
				(font
					(size 0.7 0.7)
					(thickness 0.15)
				)
				(justify mirror)
			)
		)
		(property "Value" "R_0R_0402"
			(at -1.011843 -1.772047 270)
			(layer "B.Fab")
			(effects
				(font
					(size 0.7 0.7)
					(thickness 0.15)
				)
				(justify left bottom mirror)
			)
		)
		(property "Datasheet" "https://industrial.panasonic.com/cdbs/www-data/pdf/RDA0000/AOA0000C301.pdf"
			(at 0 0 270)
			(layer "B.Fab")
			(hide yes)
			(effects
				(font
					(size 1.27 1.27)
					(thickness 0.15)
				)
				(justify mirror)
			)
		)
		(property "MPN" "ERJ2GE0R00X"
			(at 0 0 90)
			(unlocked yes)
			(layer "B.Fab")
			(hide yes)
			(effects
				(font
					(size 1 1)
					(thickness 0.15)
				)
				(justify mirror)
			)
		)
		(property "Manufacturer" "Panasonic"
			(at 0 0 90)
			(unlocked yes)
			(layer "B.Fab")
			(hide yes)
			(effects
				(font
					(size 1 1)
					(thickness 0.15)
				)
				(justify mirror)
			)
		)
		(property "License" "Apache-2.0"
			(at 0 0 90)
			(unlocked yes)
			(layer "B.Fab")
			(hide yes)
			(effects
				(font
					(size 1 1)
					(thickness 0.15)
				)
				(justify mirror)
			)
		)
		(property "Author" "Antmicro"
			(at 0 0 90)
			(unlocked yes)
			(layer "B.Fab")
			(hide yes)
			(effects
				(font
					(size 1 1)
					(thickness 0.15)
				)
				(justify mirror)
			)
		)
		(property "Val" "0R"
			(at 0 0 90)
			(unlocked yes)
			(layer "B.Fab")
			(hide yes)
			(effects
				(font
					(size 1 1)
					(thickness 0.15)
				)
				(justify mirror)
			)
		)
		(property "Tolerance" "~"
			(at 0 0 90)
			(unlocked yes)
			(layer "B.Fab")
			(hide yes)
			(effects
				(font
					(size 1 1)
					(thickness 0.15)
				)
				(justify mirror)
			)
		)
		(property "Current" "1A"
			(at 0 0 90)
			(unlocked yes)
			(layer "B.Fab")
			(hide yes)
			(effects
				(font
					(size 1 1)
					(thickness 0.15)
				)
				(justify mirror)
			)
		)
		(sheetname "/FPGA banks HP/")
		(sheetfile "fpga-hp-banks.kicad_sch")
		(attr smd)
		(fp_rect
			(start -0.925 0.47)
			(end 0.925 -0.47)
			(stroke
				(width 0.05)
				(type default)
			)
			(fill no)
			(layer "B.CrtYd")
		)
		(fp_rect
			(start -0.5 0.25)
			(end 0.5 -0.25)
			(stroke
				(width 0.15)
				(type solid)
			)
			(fill no)
			(layer "B.Fab")
		)
		(fp_text user "Author: Antmicro"
			(at -0.95 -4.169 270)
			(layer "B.Fab")
			(effects
				(font
					(size 0.7 0.7)
					(thickness 0.15)
				)
				(justify left bottom mirror)
			)
		)
		(fp_text user "License: Apache-2.0"
			(at -0.95 -5.169 270)
			(layer "B.Fab")
			(effects
				(font
					(size 0.7 0.7)
					(thickness 0.15)
				)
				(justify left bottom mirror)
			)
		)
		(fp_text user "${REFERENCE}"
			(at -0.95 -3.168 270)
			(layer "B.Fab")
			(effects
				(font
					(size 0.7 0.7)
					(thickness 0.15)
				)
				(justify left bottom mirror)
			)
		)
		(pad "1" smd roundrect
			(at -0.48 0 90)
			(size 0.59 0.64)
			(layers "B.Cu" "B.Mask" "B.Paste")
			(roundrect_rratio 0.25)
			(net 545 "/FPGA banks HP/VREF_66")
			(pintype "passive")
		)
		(pad "2" smd roundrect
			(at 0.48 0 90)
			(size 0.59 0.64)
			(layers "B.Cu" "B.Mask" "B.Paste")
			(roundrect_rratio 0.25)
			(net 826 "/FPGA banks HP/VREF")
			(pintype "passive")
		)
	)
)
